(kicad_pcb
	(version 20241229)
	(generator "pcbnew")
	(generator_version "9.0")
	(general
		(thickness 1.599998)
		(legacy_teardrops no)
	)
	(paper "A4")
	(title_block
		(date "2023-02-12")
		(rev "1.1.5")
		(comment 9 "footprints 215-219 of 473")
	)
	(layers
		(0 "F.Cu" signal)
		(4 "In1.Cu" power "In1.GND")
		(6 "In2.Cu" signal)
		(8 "In3.Cu" power "In3.GND")
		(10 "In4.Cu" power "In4.VCC")
		(12 "In5.Cu" signal)
		(14 "In6.Cu" power "In6.VCC")
		(2 "B.Cu" signal)
		(9 "F.Adhes" user "F.Adhesive")
		(11 "B.Adhes" user "B.Adhesive")
		(13 "F.Paste" user)
		(15 "B.Paste" user)
		(5 "F.SilkS" user "F.Silkscreen")
		(7 "B.SilkS" user "B.Silkscreen")
		(1 "F.Mask" user)
		(3 "B.Mask" user)
		(17 "Dwgs.User" user "User.Drawings")
		(19 "Cmts.User" user "User.Comments")
		(21 "Eco1.User" user "User.Eco1")
		(23 "Eco2.User" user "User.Eco2")
		(25 "Edge.Cuts" user)
		(27 "Margin" user)
		(31 "F.CrtYd" user "F.Courtyard")
		(29 "B.CrtYd" user "B.Courtyard")
		(35 "F.Fab" user)
		(33 "B.Fab" user)
	)
	(footprint "antmicro-footprints:C_0805_2012Metric"
		(layer "F.Cu")
		(at 111.2992 128.9)
		(descr "Capacitor SMD 0805")
		(tags "capacitor SMD 0805")
		(property "Reference" "C125"
			(at -1.5992 0.1 135)
			(layer "F.SilkS")
			(effects
				(font
					(size 0.7 0.7)
					(thickness 0.15)
				)
				(justify left bottom)
			)
		)
		(property "Value" "C_22u_0805_16V"
			(at 0 1.947 0)
			(layer "F.Fab")
			(effects
				(font
					(size 0.7 0.7)
					(thickness 0.15)
				)
				(justify left bottom)
			)
		)
		(property "Description" " "
			(at 0 0 0)
			(layer "F.Fab")
			(hide yes)
			(effects
				(font
					(size 1.27 1.27)
					(thickness 0.15)
				)
			)
		)
		(property "Author" "Antmicro"
			(at 0 0 0)
			(layer "F.Fab")
			(hide yes)
			(effects
				(font
					(size 1 1)
					(thickness 0.15)
				)
			)
		)
		(property "Dielectric" ""
			(at 0 0 0)
			(layer "F.Fab")
			(hide yes)
			(effects
				(font
					(size 1 1)
					(thickness 0.15)
				)
			)
		)
		(property "License" "Apache-2.0"
			(at 0 0 0)
			(layer "F.Fab")
			(hide yes)
			(effects
				(font
					(size 1 1)
					(thickness 0.15)
				)
			)
		)
		(property "MPN" "GRT21BR61C226ME13L"
			(at 0 0 0)
			(layer "F.Fab")
			(hide yes)
			(effects
				(font
					(size 1 1)
					(thickness 0.15)
				)
			)
		)
		(property "Manufacturer" "Murata"
			(at 0 0 0)
			(layer "F.Fab")
			(hide yes)
			(effects
				(font
					(size 1 1)
					(thickness 0.15)
				)
			)
		)
		(property "Val" "22u/16V"
			(at 0 0 0)
			(layer "F.Fab")
			(hide yes)
			(effects
				(font
					(size 1 1)
					(thickness 0.15)
				)
			)
		)
		(property "Voltage" ""
			(at 0 0 0)
			(layer "F.Fab")
			(hide yes)
			(effects
				(font
					(size 1 1)
					(thickness 0.15)
				)
			)
		)
		(sheetname "Supply")
		(sheetfile "supply.kicad_sch")
		(attr smd)
		(fp_line
			(start -0.3 -0.8)
			(end 0.3 -0.8)
			(stroke
				(width 0.15)
				(type solid)
			)
			(layer "F.SilkS")
		)
		(fp_line
			(start -0.3 0.8)
			(end 0.3 0.8)
			(stroke
				(width 0.15)
				(type solid)
			)
			(layer "F.SilkS")
		)
		(fp_rect
			(start -1.9 -0.93)
			(end 1.9 0.93)
			(stroke
				(width 0.05)
				(type solid)
			)
			(fill no)
			(layer "F.CrtYd")
		)
		(fp_rect
			(start -0.95 -0.675)
			(end 0.95 0.675)
			(stroke
				(width 0.15)
				(type solid)
			)
			(fill no)
			(layer "F.Fab")
		)
		(pad "1" smd rect
			(at -1.05 0)
			(size 1.2 1.2)
			(layers "F.Cu" "F.Mask" "F.Paste")
			(net 224 "VIN")
			(pintype "passive")
		)
		(pad "2" smd rect
			(at 1.05 0)
			(size 1.2 1.2)
			(layers "F.Cu" "F.Mask" "F.Paste")
			(net 5 "GND")
			(pintype "passive")
		)
	)
	(footprint "antmicro-footprints:R_0402_1005Metric"
		(layer "F.Cu")
		(at 111.94 101.449 180)
		(descr "Resistor SMD 0402")
		(tags "resistor SMD 0402")
		(property "Reference" "R135"
			(at 3.64 -0.351 180)
			(layer "F.SilkS")
			(effects
				(font
					(size 0.7 0.7)
					(thickness 0.15)
				)
				(justify left bottom)
			)
		)
		(property "Value" "R_10k_0402"
			(at 0 1.4 180)
			(layer "F.Fab")
			(effects
				(font
					(size 0.7 0.7)
					(thickness 0.15)
				)
				(justify left bottom)
			)
		)
		(property "Description" "10k resistor in 0402 package with 1% tolerance"
			(at 0 0 180)
			(layer "F.Fab")
			(hide yes)
			(effects
				(font
					(size 1.27 1.27)
					(thickness 0.15)
				)
			)
		)
		(property "Author" "Antmicro"
			(at 223.88 202.898 0)
			(layer "F.Fab")
			(hide yes)
			(effects
				(font
					(size 1 1)
					(thickness 0.15)
				)
			)
		)
		(property "License" "Apache-2.0"
			(at 223.88 202.898 0)
			(layer "F.Fab")
			(hide yes)
			(effects
				(font
					(size 1 1)
					(thickness 0.15)
				)
			)
		)
		(property "MPN" "CR0402-FX-1002GLF"
			(at 223.88 202.898 0)
			(layer "F.Fab")
			(hide yes)
			(effects
				(font
					(size 1 1)
					(thickness 0.15)
				)
			)
		)
		(property "Manufacturer" "Bourns"
			(at 223.88 202.898 0)
			(layer "F.Fab")
			(hide yes)
			(effects
				(font
					(size 1 1)
					(thickness 0.15)
				)
			)
		)
		(property "Tolerance" "1%"
			(at 223.88 202.898 0)
			(layer "F.Fab")
			(hide yes)
			(effects
				(font
					(size 1 1)
					(thickness 0.15)
				)
			)
		)
		(property "Val" "10k"
			(at 223.88 202.898 0)
			(layer "F.Fab")
			(hide yes)
			(effects
				(font
					(size 1 1)
					(thickness 0.15)
				)
			)
		)
		(sheetname "Supply")
		(sheetfile "supply.kicad_sch")
		(attr smd)
		(fp_rect
			(start -0.93 -0.47)
			(end 0.93 0.47)
			(stroke
				(width 0.05)
				(type solid)
			)
			(fill no)
			(layer "F.CrtYd")
		)
		(fp_rect
			(start -0.5 -0.25)
			(end 0.5 0.25)
			(stroke
				(width 0.15)
				(type solid)
			)
			(fill no)
			(layer "F.Fab")
		)
		(pad "1" smd roundrect
			(at -0.485 0 180)
			(size 0.59 0.64)
			(layers "F.Cu" "F.Mask" "F.Paste")
			(roundrect_rratio 0.25)
			(net 578 "/Supply/3V3_FB")
			(pintype "passive")
		)
		(pad "2" smd roundrect
			(at 0.485 0 180)
			(size 0.59 0.64)
			(layers "F.Cu" "F.Mask" "F.Paste")
			(roundrect_rratio 0.25)
			(net 5 "GND")
			(pintype "passive")
		)
	)
	(footprint "antmicro-footprints:R_0402_1005Metric"
		(layer "F.Cu")
		(at 117.7 87.049 180)
		(descr "Resistor SMD 0402")
		(tags "resistor SMD 0402")
		(property "Reference" "R157"
			(at 0.897806 3.574 180)
			(layer "F.SilkS")
			(effects
				(font
					(size 0.7 0.7)
					(thickness 0.15)
				)
				(justify left bottom)
			)
		)
		(property "Value" "R_100k_0402"
			(at 0 1.4 180)
			(layer "F.Fab")
			(effects
				(font
					(size 0.7 0.7)
					(thickness 0.15)
				)
				(justify left bottom)
			)
		)
		(property "Description" "100k resistor in 0402 package with 1% tolerance"
			(at 0 0 180)
			(layer "F.Fab")
			(hide yes)
			(effects
				(font
					(size 1.27 1.27)
					(thickness 0.15)
				)
			)
		)
		(property "Author" "Antmicro"
			(at 235.4 174.098 0)
			(layer "F.Fab")
			(hide yes)
			(effects
				(font
					(size 1 1)
					(thickness 0.15)
				)
			)
		)
		(property "License" "Apache-2.0"
			(at 235.4 174.098 0)
			(layer "F.Fab")
			(hide yes)
			(effects
				(font
					(size 1 1)
					(thickness 0.15)
				)
			)
		)
		(property "MPN" "CR0402-FX-1003GLF"
			(at 235.4 174.098 0)
			(layer "F.Fab")
			(hide yes)
			(effects
				(font
					(size 1 1)
					(thickness 0.15)
				)
			)
		)
		(property "Manufacturer" "Bourns"
			(at 235.4 174.098 0)
			(layer "F.Fab")
			(hide yes)
			(effects
				(font
					(size 1 1)
					(thickness 0.15)
				)
			)
		)
		(property "Tolerance" "1%"
			(at 235.4 174.098 0)
			(layer "F.Fab")
			(hide yes)
			(effects
				(font
					(size 1 1)
					(thickness 0.15)
				)
			)
		)
		(property "Val" "100k"
			(at 235.4 174.098 0)
			(layer "F.Fab")
			(hide yes)
			(effects
				(font
					(size 1 1)
					(thickness 0.15)
				)
			)
		)
		(sheetname "Supply")
		(sheetfile "supply.kicad_sch")
		(attr smd)
		(fp_rect
			(start -0.93 -0.47)
			(end 0.93 0.47)
			(stroke
				(width 0.05)
				(type solid)
			)
			(fill no)
			(layer "F.CrtYd")
		)
		(fp_rect
			(start -0.5 -0.25)
			(end 0.5 0.25)
			(stroke
				(width 0.15)
				(type solid)
			)
			(fill no)
			(layer "F.Fab")
		)
		(pad "1" smd roundrect
			(at -0.485 0 180)
			(size 0.59 0.64)
			(layers "F.Cu" "F.Mask" "F.Paste")
			(roundrect_rratio 0.25)
			(net 595 "/Supply/1V8_VCC_INT")
			(pintype "passive")
		)
		(pad "2" smd roundrect
			(at 0.485 0 180)
			(size 0.59 0.64)
			(layers "F.Cu" "F.Mask" "F.Paste")
			(roundrect_rratio 0.25)
			(net 605 "/Supply/1V8_PG")
			(pintype "passive")
		)
	)
	(footprint "antmicro-footprints:PinHeader_1x3_P2.54mm_Horizontal"
		(layer "F.Cu")
		(at 142.97 56.38 90)
		(descr "Through hole angled pin header, 1x03, 2.54mm pitch, 6mm pin length, single row")
		(tags "Through hole angled pin header THT 1x03 2.54mm single row")
		(property "Reference" "J7"
			(at 2.38 6.83 180)
			(layer "F.SilkS")
			(effects
				(font
					(size 0.7 0.7)
					(thickness 0.15)
				)
				(justify left bottom)
			)
		)
		(property "Value" "PinHeader_1x3_P2.54mm_Drill1.1mm_Horizontal"
			(at -5.5 7.6 90)
			(layer "F.Fab")
			(effects
				(font
					(size 0.7 0.7)
					(thickness 0.15)
				)
				(justify left bottom)
			)
		)
		(property "Description" "Connector Header Through Hole, Right Angle 3 position 0.100\" (2.54mm)"
			(at 0 0 90)
			(layer "F.Fab")
			(hide yes)
			(effects
				(font
					(size 1.27 1.27)
					(thickness 0.15)
				)
			)
		)
		(property "Author" "Antmicro"
			(at 199.35 -86.59 0)
			(layer "F.Fab")
			(hide yes)
			(effects
				(font
					(size 1 1)
					(thickness 0.15)
				)
			)
		)
		(property "License" "Apache-2.0"
			(at 199.35 -86.59 0)
			(layer "F.Fab")
			(hide yes)
			(effects
				(font
					(size 1 1)
					(thickness 0.15)
				)
			)
		)
		(property "MPN" "61300311021"
			(at 199.35 -86.59 0)
			(layer "F.Fab")
			(hide yes)
			(effects
				(font
					(size 1 1)
					(thickness 0.15)
				)
			)
		)
		(property "Manufacturer" "Würth Elektronik"
			(at 199.35 -86.59 0)
			(layer "F.Fab")
			(hide yes)
			(effects
				(font
					(size 1 1)
					(thickness 0.15)
				)
			)
		)
		(sheetname "Supply")
		(sheetfile "supply.kicad_sch")
		(attr through_hole)
		(fp_line
			(start 4.099 -1.331)
			(end 1.439 -1.331)
			(stroke
				(width 0.15)
				(type solid)
			)
			(layer "F.SilkS")
		)
		(fp_line
			(start 1.439 -1.331)
			(end 1.439 6.41)
			(stroke
				(width 0.15)
				(type solid)
			)
			(layer "F.SilkS")
		)
		(fp_line
			(start 10.098 -0.38)
			(end 10.098 0.378)
			(stroke
				(width 0.15)
				(type solid)
			)
			(layer "F.SilkS")
		)
		(fp_line
			(start 4.099 -0.38)
			(end 10.098 -0.38)
			(stroke
				(width 0.15)
				(type solid)
			)
			(layer "F.SilkS")
		)
		(fp_line
			(start 1.11 -0.38)
			(end 1.439 -0.38)
			(stroke
				(width 0.15)
				(type solid)
			)
			(layer "F.SilkS")
		)
		(fp_line
			(start 4.099 -0.32)
			(end 10.098 -0.32)
			(stroke
				(width 0.15)
				(type solid)
			)
			(layer "F.SilkS")
		)
		(fp_line
			(start 4.099 -0.202)
			(end 10.098 -0.202)
			(stroke
				(width 0.15)
				(type solid)
			)
			(layer "F.SilkS")
		)
		(fp_line
			(start 4.099 -0.08)
			(end 10.098 -0.08)
			(stroke
				(width 0.15)
				(type solid)
			)
			(layer "F.SilkS")
		)
		(fp_line
			(start 4.099 0.04)
			(end 10.098 0.04)
			(stroke
				(width 0.15)
				(type solid)
			)
			(layer "F.SilkS")
		)
		(fp_line
			(start 4.099 0.16)
			(end 10.098 0.16)
			(stroke
				(width 0.15)
				(type solid)
			)
			(layer "F.SilkS")
		)
		(fp_line
			(start 4.099 0.28)
			(end 10.098 0.28)
			(stroke
				(width 0.15)
				(type solid)
			)
			(layer "F.SilkS")
		)
		(fp_line
			(start 10.098 0.378)
			(end 4.099 0.378)
			(stroke
				(width 0.15)
				(type solid)
			)
			(layer "F.SilkS")
		)
		(fp_line
			(start 1.11 0.378)
			(end 1.439 0.378)
			(stroke
				(width 0.15)
				(type solid)
			)
			(layer "F.SilkS")
		)
		(fp_line
			(start 1.439 1.269)
			(end 4.099 1.269)
			(stroke
				(width 0.15)
				(type solid)
			)
			(layer "F.SilkS")
		)
		(fp_line
			(start 10.098 2.16)
			(end 10.098 2.918)
			(stroke
				(width 0.15)
				(type solid)
			)
			(layer "F.SilkS")
		)
		(fp_line
			(start 4.099 2.16)
			(end 10.098 2.16)
			(stroke
				(width 0.15)
				(type solid)
			)
			(layer "F.SilkS")
		)
		(fp_line
			(start 1.042 2.16)
			(end 1.439 2.16)
			(stroke
				(width 0.15)
				(type solid)
			)
			(layer "F.SilkS")
		)
		(fp_line
			(start 10.098 2.918)
			(end 4.099 2.918)
			(stroke
				(width 0.15)
				(type solid)
			)
			(layer "F.SilkS")
		)
		(fp_line
			(start 1.042 2.918)
			(end 1.439 2.918)
			(stroke
				(width 0.15)
				(type solid)
			)
			(layer "F.SilkS")
		)
		(fp_line
			(start 1.439 3.809)
			(end 4.099 3.809)
			(stroke
				(width 0.15)
				(type solid)
			)
			(layer "F.SilkS")
		)
		(fp_line
			(start 10.098 4.7)
			(end 10.098 5.459)
			(stroke
				(width 0.15)
				(type solid)
			)
			(layer "F.SilkS")
		)
		(fp_line
			(start 4.099 4.7)
			(end 10.098 4.7)
			(stroke
				(width 0.15)
				(type solid)
			)
			(layer "F.SilkS")
		)
		(fp_line
			(start 1.042 4.7)
			(end 1.439 4.7)
			(stroke
				(width 0.15)
				(type solid)
			)
			(layer "F.SilkS")
		)
		(fp_line
			(start 10.098 5.459)
			(end 4.099 5.459)
			(stroke
				(width 0.15)
				(type solid)
			)
			(layer "F.SilkS")
		)
		(fp_line
			(start 1.042 5.459)
			(end 1.439 5.459)
			(stroke
				(width 0.15)
				(type solid)
			)
			(layer "F.SilkS")
		)
		(fp_line
			(start 4.099 6.41)
			(end 4.099 -1.331)
			(stroke
				(width 0.15)
				(type solid)
			)
			(layer "F.SilkS")
		)
		(fp_line
			(start 1.439 6.41)
			(end 4.099 6.41)
			(stroke
				(width 0.15)
				(type solid)
			)
			(layer "F.SilkS")
		)
		(fp_circle
			(center -1.3 0)
			(end -1.25 0)
			(stroke
				(width 0.15)
				(type solid)
			)
			(fill yes)
			(layer "F.SilkS")
		)
		(fp_rect
			(start -0.82 -1.77)
			(end 10.538 6.849)
			(stroke
				(width 0.05)
				(type solid)
			)
			(fill no)
			(layer "F.CrtYd")
		)
		(fp_line
			(start 4.038 -1.27)
			(end 4.038 6.349)
			(stroke
				(width 0.15)
				(type solid)
			)
			(layer "F.Fab")
		)
		(fp_line
			(start 2.133 -1.27)
			(end 4.038 -1.27)
			(stroke
				(width 0.15)
				(type solid)
			)
			(layer "F.Fab")
		)
		(fp_line
			(start 1.499 -0.635)
			(end 2.133 -1.27)
			(stroke
				(width 0.15)
				(type solid)
			)
			(layer "F.Fab")
		)
		(fp_line
			(start 10.038 -0.32)
			(end 10.038 0.32)
			(stroke
				(width 0.15)
				(type solid)
			)
			(layer "F.Fab")
		)
		(fp_line
			(start 4.038 -0.32)
			(end 10.038 -0.32)
			(stroke
				(width 0.15)
				(type solid)
			)
			(layer "F.Fab")
		)
		(fp_line
			(start -0.32 -0.32)
			(end 1.499 -0.32)
			(stroke
				(width 0.15)
				(type solid)
			)
			(layer "F.Fab")
		)
		(fp_line
			(start -0.32 -0.32)
			(end -0.32 0.32)
			(stroke
				(width 0.15)
				(type solid)
			)
			(layer "F.Fab")
		)
		(fp_line
			(start 4.038 0.32)
			(end 10.038 0.32)
			(stroke
				(width 0.15)
				(type solid)
			)
			(layer "F.Fab")
		)
		(fp_line
			(start -0.32 0.32)
			(end 1.499 0.32)
			(stroke
				(width 0.15)
				(type solid)
			)
			(layer "F.Fab")
		)
		(fp_line
			(start 10.038 2.22)
			(end 10.038 2.858)
			(stroke
				(width 0.15)
				(type solid)
			)
			(layer "F.Fab")
		)
		(fp_line
			(start 4.038 2.22)
			(end 10.038 2.22)
			(stroke
				(width 0.15)
				(type solid)
			)
			(layer "F.Fab")
		)
		(fp_line
			(start -0.32 2.22)
			(end 1.499 2.22)
			(stroke
				(width 0.15)
				(type solid)
			)
			(layer "F.Fab")
		)
		(fp_line
			(start -0.32 2.22)
			(end -0.32 2.858)
			(stroke
				(width 0.15)
				(type solid)
			)
			(layer "F.Fab")
		)
		(fp_line
			(start 4.038 2.858)
			(end 10.038 2.858)
			(stroke
				(width 0.15)
				(type solid)
			)
			(layer "F.Fab")
		)
		(fp_line
			(start -0.32 2.858)
			(end 1.499 2.858)
			(stroke
				(width 0.15)
				(type solid)
			)
			(layer "F.Fab")
		)
		(fp_line
			(start 10.038 4.759)
			(end 10.038 5.4)
			(stroke
				(width 0.15)
				(type solid)
			)
			(layer "F.Fab")
		)
		(fp_line
			(start 4.038 4.759)
			(end 10.038 4.759)
			(stroke
				(width 0.15)
				(type solid)
			)
			(layer "F.Fab")
		)
		(fp_line
			(start -0.32 4.759)
			(end 1.499 4.759)
			(stroke
				(width 0.15)
				(type solid)
			)
			(layer "F.Fab")
		)
		(fp_line
			(start -0.32 4.759)
			(end -0.32 5.4)
			(stroke
				(width 0.15)
				(type solid)
			)
			(layer "F.Fab")
		)
		(fp_line
			(start 4.038 5.4)
			(end 10.038 5.4)
			(stroke
				(width 0.15)
				(type solid)
			)
			(layer "F.Fab")
		)
		(fp_line
			(start -0.32 5.4)
			(end 1.499 5.4)
			(stroke
				(width 0.15)
				(type solid)
			)
			(layer "F.Fab")
		)
		(fp_line
			(start 4.038 6.349)
			(end 1.499 6.349)
			(stroke
				(width 0.15)
				(type solid)
			)
			(layer "F.Fab")
		)
		(fp_line
			(start 1.499 6.349)
			(end 1.499 -0.635)
			(stroke
				(width 0.15)
				(type solid)
			)
			(layer "F.Fab")
		)
		(pad "1" thru_hole rect
			(at 0 0 90)
			(size 1.7 1.7)
			(drill 1)
			(layers "*.Cu" "*.Mask")
			(remove_unused_layers no)
			(net 273 "1V1_DDR")
			(pintype "passive")
		)
		(pad "2" thru_hole oval
			(at 0 2.539 90)
			(size 1.7 1.7)
			(drill 1)
			(layers "*.Cu" "*.Mask")
			(remove_unused_layers no)
			(net 66 "VDDQ")
			(pintype "passive")
		)
		(pad "3" thru_hole oval
			(at 0 5.078 90)
			(size 1.7 1.7)
			(drill 1)
			(layers "*.Cu" "*.Mask")
			(remove_unused_layers no)
			(net 640 "0V6_DDR")
			(pintype "passive")
		)
	)
	(footprint "lpddr4-test-board-footprints:mounting-hole-3.2mm"
		(layer "F.Cu")
		(at 213.9 132.9)
		(property "Reference" "MH3"
			(at -0.178 4.025 0)
			(layer "F.SilkS")
			(hide yes)
			(effects
				(font
					(size 0.7 0.7)
					(thickness 0.15)
				)
				(justify left bottom)
			)
		)
		(property "Value" "M3.2"
			(at -0.153 -4.153 0)
			(layer "F.Fab")
			(hide yes)
			(effects
				(font
					(size 0.7 0.7)
					(thickness 0.15)
				)
				(justify left bottom)
			)
		)
		(attr through_hole board_only exclude_from_bom)
		(pad "1" thru_hole circle
			(at 0 0)
			(size 6 6)
			(drill 3.2)
			(layers "*.Cu" "*.Mask")
			(remove_unused_layers no)
		)
	)
)
